(kicad_pcb
	(version 20260206)
	(generator "pcbnew")
	(generator_version "10.0")
	(general
		(thickness 1.6)
		(legacy_teardrops no)
	)
	(paper "A4")
	(title_block
		(title "v1-chassis-manager — T6M_CM_d_v01_1031_1645.brd")
		(comment 1 "Open CloudServer (Microsoft) / footprints 1208-1217 of 2512")
	)
	(layers
		(0 "F.Cu" signal "TOP")
		(4 "In1.Cu" signal "GND1")
		(6 "In2.Cu" signal "IN1")
		(8 "In3.Cu" signal "VCC1")
		(10 "In4.Cu" signal "VCC2")
		(12 "In5.Cu" signal "GND2")
		(14 "In6.Cu" signal "IN2")
		(16 "In7.Cu" signal "IN3")
		(18 "In8.Cu" signal "GND3")
		(2 "B.Cu" signal "BOTTOM")
		(9 "F.Adhes" user "F.Adhesive")
		(11 "B.Adhes" user "B.Adhesive")
		(13 "F.Paste" user "Package Geometry/Pastemask Top")
		(15 "B.Paste" user "Package Geometry/Pastemask Bottom")
		(5 "F.SilkS" user "Ref Des/Silkscreen Top")
		(7 "B.SilkS" user "Ref Des/Silkscreen Bottom")
		(1 "F.Mask" user "Board Geometry/Soldermask Top")
		(3 "B.Mask" user "Board Geometry/Soldermask Bottom")
		(17 "Dwgs.User" user "User.Drawings")
		(19 "Cmts.User" user "User.Comments")
		(21 "Eco1.User" user "User.Eco1")
		(23 "Eco2.User" user "User.Eco2")
		(25 "Edge.Cuts" user "Board Geometry/Outline")
		(27 "Margin" user)
		(31 "F.CrtYd" user "Package Geometry/Place Bound Top")
		(29 "B.CrtYd" user "Package Geometry/Place Bound Bottom")
		(35 "F.Fab" user "Ref Des/Assembly Top")
		(33 "B.Fab" user "Ref Des/Assembly Bottom")
	)
	(footprint ""
		(layer "F.Cu")
		(at 114.52225 -153.548588)
		(property "Reference" "C887"
			(at -0.011684 1.914144 0)
			(unlocked yes)
			(layer "F.SilkS")
			(effects
				(font
					(size 0.635 0.4064)
					(thickness 0.1524)
				)
			)
		)
		(property "Value" ""
			(at 0 0 0)
			(layer "F.Fab")
			(effects
				(font
					(size 1.27 1.27)
				)
			)
		)
		(duplicate_pad_numbers_are_jumpers no)
		(fp_line
			(start -1.2954 -0.5842)
			(end 1.2954 -0.5842)
			(stroke
				(width 0.1524)
				(type default)
			)
			(layer "F.SilkS")
		)
		(fp_line
			(start -1.2954 0.5842)
			(end -1.2954 -0.5842)
			(stroke
				(width 0.1524)
				(type default)
			)
			(layer "F.SilkS")
		)
		(fp_line
			(start 0 -0.5842)
			(end 0 0.5842)
			(stroke
				(width 0.1524)
				(type default)
			)
			(layer "F.SilkS")
		)
		(fp_line
			(start 1.2954 -0.5842)
			(end 1.2954 0.5842)
			(stroke
				(width 0.1524)
				(type default)
			)
			(layer "F.SilkS")
		)
		(fp_line
			(start 1.2954 0.5842)
			(end -1.2954 0.5842)
			(stroke
				(width 0.1524)
				(type default)
			)
			(layer "F.SilkS")
		)
		(fp_poly
			(pts
				(xy 0.8636 -0.4572) (xy 0.8636 -0.3556) (xy 1.143 -0.3556) (xy 1.143 0.3556) (xy 0.8636 0.3556)
				(xy 0.8636 0.4572) (xy -0.8636 0.4572) (xy -0.8636 0.3556) (xy -1.143 0.3556) (xy -1.143 -0.3556)
				(xy -0.8636 -0.3556) (xy -0.8636 -0.4572)
			)
			(stroke
				(width 0)
				(type default)
			)
			(fill no)
			(layer "F.CrtYd")
		)
		(fp_line
			(start -0.884936 -0.504952)
			(end 0.884936 -0.504952)
			(stroke
				(width 0.1)
				(type default)
			)
			(layer "F.Fab")
		)
		(fp_line
			(start -0.884936 0.504952)
			(end -0.884936 -0.504952)
			(stroke
				(width 0.1)
				(type default)
			)
			(layer "F.Fab")
		)
		(fp_line
			(start 0.884936 -0.504952)
			(end 0.884936 0.504952)
			(stroke
				(width 0.1)
				(type default)
			)
			(layer "F.Fab")
		)
		(fp_line
			(start 0.884936 0.504952)
			(end -0.884936 0.504952)
			(stroke
				(width 0.1)
				(type default)
			)
			(layer "F.Fab")
		)
		(pad "1" smd rect
			(at 0.7366 0 90)
			(size 0.7112 0.8128)
			(layers "F.Cu" "F.Mask" "F.Paste")
			(net "GND")
		)
		(pad "2" smd rect
			(at -0.7366 0 90)
			(size 0.7112 0.8128)
			(layers "F.Cu" "F.Mask" "F.Paste")
			(net "N52410978")
		)
	)
	(footprint ""
		(layer "F.Cu")
		(at 191.369442 -115.705128 180)
		(property "Reference" "R1026"
			(at -1.524254 -0.157734 0)
			(unlocked yes)
			(layer "F.SilkS")
			(effects
				(font
					(size 0.7874 0.5842)
					(thickness 0.1524)
				)
				(justify left)
			)
		)
		(property "Value" ""
			(at 0 0 180)
			(layer "F.Fab")
			(effects
				(font
					(size 1.27 1.27)
				)
			)
		)
		(duplicate_pad_numbers_are_jumpers no)
		(fp_line
			(start 0.7874 0.4064)
			(end -0.7874 0.4064)
			(stroke
				(width 0.1524)
				(type default)
			)
			(layer "F.SilkS")
		)
		(fp_line
			(start 0.7874 -0.4064)
			(end 0.7874 0.4064)
			(stroke
				(width 0.1524)
				(type default)
			)
			(layer "F.SilkS")
		)
		(fp_line
			(start -0.7874 0.4064)
			(end -0.7874 -0.4064)
			(stroke
				(width 0.1524)
				(type default)
			)
			(layer "F.SilkS")
		)
		(fp_line
			(start -0.7874 -0.4064)
			(end 0.7874 -0.4064)
			(stroke
				(width 0.1524)
				(type default)
			)
			(layer "F.SilkS")
		)
		(fp_poly
			(pts
				(xy -0.508 0.2794) (xy -0.508 0.2286) (xy -0.635 0.2286) (xy -0.635 -0.254) (xy -0.5334 -0.254)
				(xy -0.5334 -0.2794) (xy 0.5334 -0.2794) (xy 0.5334 -0.254) (xy 0.635 -0.254) (xy 0.635 0.254) (xy 0.5334 0.254)
				(xy 0.5334 0.2794)
			)
			(stroke
				(width 0)
				(type default)
			)
			(fill no)
			(layer "F.CrtYd")
		)
		(pad "1" smd rect
			(at 0.40005 0 180)
			(size 0.4572 0.508)
			(layers "F.Cu" "F.Mask" "F.Paste")
			(net "P12V_NODE1_PWRGD_EN")
		)
		(pad "2" smd rect
			(at -0.40005 0 180)
			(size 0.4572 0.508)
			(layers "F.Cu" "F.Mask" "F.Paste")
			(net "P12V_AUX")
		)
	)
	(footprint ""
		(layer "F.Cu")
		(at 143.105886 -53.513228 180)
		(property "Reference" "R1016"
			(at -1.112266 0.915416 0)
			(unlocked yes)
			(layer "F.SilkS")
			(effects
				(font
					(size 0.7874 0.5842)
					(thickness 0.1524)
				)
				(justify left)
			)
		)
		(property "Value" ""
			(at 0 0 180)
			(layer "F.Fab")
			(effects
				(font
					(size 1.27 1.27)
				)
			)
		)
		(duplicate_pad_numbers_are_jumpers no)
		(fp_line
			(start 0.7874 0.4064)
			(end -0.7874 0.4064)
			(stroke
				(width 0.1524)
				(type default)
			)
			(layer "F.SilkS")
		)
		(fp_line
			(start 0.7874 -0.4064)
			(end 0.7874 0.4064)
			(stroke
				(width 0.1524)
				(type default)
			)
			(layer "F.SilkS")
		)
		(fp_line
			(start -0.7874 0.4064)
			(end -0.7874 -0.4064)
			(stroke
				(width 0.1524)
				(type default)
			)
			(layer "F.SilkS")
		)
		(fp_line
			(start -0.7874 -0.4064)
			(end 0.7874 -0.4064)
			(stroke
				(width 0.1524)
				(type default)
			)
			(layer "F.SilkS")
		)
		(fp_poly
			(pts
				(xy -0.508 0.2794) (xy -0.508 0.2286) (xy -0.635 0.2286) (xy -0.635 -0.254) (xy -0.5334 -0.254)
				(xy -0.5334 -0.2794) (xy 0.5334 -0.2794) (xy 0.5334 -0.254) (xy 0.635 -0.254) (xy 0.635 0.254) (xy 0.5334 0.254)
				(xy 0.5334 0.2794)
			)
			(stroke
				(width 0)
				(type default)
			)
			(fill no)
			(layer "F.CrtYd")
		)
		(pad "1" smd rect
			(at 0.40005 0 180)
			(size 0.4572 0.508)
			(layers "F.Cu" "F.Mask" "F.Paste")
			(net "GND")
		)
		(pad "2" smd rect
			(at -0.40005 0 180)
			(size 0.4572 0.508)
			(layers "F.Cu" "F.Mask" "F.Paste")
			(net "UART_DTR_P2_N")
		)
	)
	(footprint ""
		(layer "F.Cu")
		(at 162.873944 -93.840808 -90)
		(property "Reference" "R523"
			(at 1.2192 4.223512 90)
			(unlocked yes)
			(layer "F.SilkS")
			(effects
				(font
					(size 0.7874 0.5842)
					(thickness 0.1524)
				)
				(justify left)
			)
		)
		(property "Value" ""
			(at 0 0 270)
			(layer "F.Fab")
			(effects
				(font
					(size 1.27 1.27)
				)
			)
		)
		(duplicate_pad_numbers_are_jumpers no)
		(fp_line
			(start -0.7874 0.4064)
			(end -0.7874 -0.4064)
			(stroke
				(width 0.1524)
				(type default)
			)
			(layer "F.SilkS")
		)
		(fp_line
			(start 0.7874 0.4064)
			(end -0.7874 0.4064)
			(stroke
				(width 0.1524)
				(type default)
			)
			(layer "F.SilkS")
		)
		(fp_line
			(start -0.7874 -0.4064)
			(end 0.7874 -0.4064)
			(stroke
				(width 0.1524)
				(type default)
			)
			(layer "F.SilkS")
		)
		(fp_line
			(start 0.7874 -0.4064)
			(end 0.7874 0.4064)
			(stroke
				(width 0.1524)
				(type default)
			)
			(layer "F.SilkS")
		)
		(fp_poly
			(pts
				(xy -0.508 0.2794) (xy -0.508 0.2286) (xy -0.635 0.2286) (xy -0.635 -0.254) (xy -0.5334 -0.254)
				(xy -0.5334 -0.2794) (xy 0.5334 -0.2794) (xy 0.5334 -0.254) (xy 0.635 -0.254) (xy 0.635 0.254) (xy 0.5334 0.254)
				(xy 0.5334 0.2794)
			)
			(stroke
				(width 0)
				(type default)
			)
			(fill no)
			(layer "F.CrtYd")
		)
		(pad "1" smd rect
			(at 0.40005 0 270)
			(size 0.4572 0.508)
			(layers "F.Cu" "F.Mask" "F.Paste")
			(net "SPI_USB_NODE1_CSB_N")
		)
		(pad "2" smd rect
			(at -0.40005 0 270)
			(size 0.4572 0.508)
			(layers "F.Cu" "F.Mask" "F.Paste")
			(net "SPI_USB_NODE1_CSB_R_L")
		)
	)
	(footprint ""
		(layer "F.Cu")
		(at 7.65556 -138.620246 -90)
		(property "Reference" "R1301"
			(at 4.242054 4.237482 90)
			(unlocked yes)
			(layer "F.SilkS")
			(effects
				(font
					(size 0.7874 0.5842)
					(thickness 0.1524)
				)
				(justify left)
			)
		)
		(property "Value" ""
			(at 0 0 270)
			(layer "F.Fab")
			(effects
				(font
					(size 1.27 1.27)
				)
			)
		)
		(duplicate_pad_numbers_are_jumpers no)
		(fp_line
			(start -0.7874 0.4064)
			(end -0.7874 -0.4064)
			(stroke
				(width 0.1524)
				(type default)
			)
			(layer "F.SilkS")
		)
		(fp_line
			(start 0.7874 0.4064)
			(end -0.7874 0.4064)
			(stroke
				(width 0.1524)
				(type default)
			)
			(layer "F.SilkS")
		)
		(fp_line
			(start -0.7874 -0.4064)
			(end 0.7874 -0.4064)
			(stroke
				(width 0.1524)
				(type default)
			)
			(layer "F.SilkS")
		)
		(fp_line
			(start 0.7874 -0.4064)
			(end 0.7874 0.4064)
			(stroke
				(width 0.1524)
				(type default)
			)
			(layer "F.SilkS")
		)
		(fp_poly
			(pts
				(xy -0.508 0.2794) (xy -0.508 0.2286) (xy -0.635 0.2286) (xy -0.635 -0.254) (xy -0.5334 -0.254)
				(xy -0.5334 -0.2794) (xy 0.5334 -0.2794) (xy 0.5334 -0.254) (xy 0.635 -0.254) (xy 0.635 0.254) (xy 0.5334 0.254)
				(xy 0.5334 0.2794)
			)
			(stroke
				(width 0)
				(type default)
			)
			(fill no)
			(layer "F.CrtYd")
		)
		(pad "1" smd rect
			(at 0.40005 0 270)
			(size 0.4572 0.508)
			(layers "F.Cu" "F.Mask" "F.Paste")
			(net "P3V3_NODE1")
		)
		(pad "2" smd rect
			(at -0.40005 0 270)
			(size 0.4572 0.508)
			(layers "F.Cu" "F.Mask" "F.Paste")
			(net "N54310545")
		)
	)
	(footprint ""
		(layer "F.Cu")
		(at 179.53863 -138.152632 180)
		(property "Reference" "C798"
			(at -2.058416 -0.136398 0)
			(unlocked yes)
			(layer "F.SilkS")
			(effects
				(font
					(size 0.7874 0.5842)
					(thickness 0.1524)
				)
				(justify left)
			)
		)
		(property "Value" ""
			(at 0 0 180)
			(layer "F.Fab")
			(effects
				(font
					(size 1.27 1.27)
				)
			)
		)
		(duplicate_pad_numbers_are_jumpers no)
		(fp_line
			(start 1.905 0.8636)
			(end -1.905 0.8636)
			(stroke
				(width 0.1524)
				(type default)
			)
			(layer "F.SilkS")
		)
		(fp_line
			(start 1.905 -0.8636)
			(end 1.905 0.8636)
			(stroke
				(width 0.1524)
				(type default)
			)
			(layer "F.SilkS")
		)
		(fp_line
			(start 0 0.8382)
			(end 0 -0.8382)
			(stroke
				(width 0.1524)
				(type default)
			)
			(layer "F.SilkS")
		)
		(fp_line
			(start -1.905 0.8636)
			(end -1.905 -0.8636)
			(stroke
				(width 0.1524)
				(type default)
			)
			(layer "F.SilkS")
		)
		(fp_line
			(start -1.905 -0.8636)
			(end 1.905 -0.8636)
			(stroke
				(width 0.1524)
				(type default)
			)
			(layer "F.SilkS")
		)
		(fp_rect
			(start -1.524 0.7366)
			(end 1.524 -0.7366)
			(stroke
				(width 0)
				(type default)
			)
			(fill no)
			(layer "F.CrtYd")
		)
		(pad "1" smd rect
			(at 0.94996 0 180)
			(size 1.1176 1.3716)
			(layers "F.Cu" "F.Mask" "F.Paste")
			(net "PWR_BTN_NODE1_C_L")
		)
		(pad "2" smd rect
			(at -0.94996 0 180)
			(size 1.1176 1.3716)
			(layers "F.Cu" "F.Mask" "F.Paste")
			(net "GND")
		)
	)
	(footprint ""
		(layer "F.Cu")
		(at 187.591954 -121.65965)
		(property "Reference" "R1035"
			(at 5.448046 18.94332 0)
			(unlocked yes)
			(layer "F.SilkS")
			(effects
				(font
					(size 0.7874 0.5842)
					(thickness 0.1524)
				)
				(justify left)
			)
		)
		(property "Value" ""
			(at 0 0 0)
			(layer "F.Fab")
			(effects
				(font
					(size 1.27 1.27)
				)
			)
		)
		(duplicate_pad_numbers_are_jumpers no)
		(fp_line
			(start -0.7874 -0.4064)
			(end 0.7874 -0.4064)
			(stroke
				(width 0.1524)
				(type default)
			)
			(layer "F.SilkS")
		)
		(fp_line
			(start -0.7874 0.4064)
			(end -0.7874 -0.4064)
			(stroke
				(width 0.1524)
				(type default)
			)
			(layer "F.SilkS")
		)
		(fp_line
			(start 0.7874 -0.4064)
			(end 0.7874 0.4064)
			(stroke
				(width 0.1524)
				(type default)
			)
			(layer "F.SilkS")
		)
		(fp_line
			(start 0.7874 0.4064)
			(end -0.7874 0.4064)
			(stroke
				(width 0.1524)
				(type default)
			)
			(layer "F.SilkS")
		)
		(fp_poly
			(pts
				(xy -0.508 0.2794) (xy -0.508 0.2286) (xy -0.635 0.2286) (xy -0.635 -0.254) (xy -0.5334 -0.254)
				(xy -0.5334 -0.2794) (xy 0.5334 -0.2794) (xy 0.5334 -0.254) (xy 0.635 -0.254) (xy 0.635 0.254) (xy 0.5334 0.254)
				(xy 0.5334 0.2794)
			)
			(stroke
				(width 0)
				(type default)
			)
			(fill no)
			(layer "F.CrtYd")
		)
		(pad "1" smd rect
			(at 0.40005 0)
			(size 0.4572 0.508)
			(layers "F.Cu" "F.Mask" "F.Paste")
			(net "P3V3_STB_NODE1")
		)
		(pad "2" smd rect
			(at -0.40005 0)
			(size 0.4572 0.508)
			(layers "F.Cu" "F.Mask" "F.Paste")
			(net "JTAG_CPLD1_TDI")
		)
	)
	(footprint ""
		(layer "F.Cu")
		(at 100.550472 -151.877268)
		(property "Reference" "PC33"
			(at -2.59334 3.216656 0)
			(unlocked yes)
			(layer "F.SilkS")
			(effects
				(font
					(size 0.7874 0.5842)
					(thickness 0.1524)
				)
				(justify left)
			)
		)
		(property "Value" ""
			(at 0 0 0)
			(layer "F.Fab")
			(effects
				(font
					(size 1.27 1.27)
				)
			)
		)
		(duplicate_pad_numbers_are_jumpers no)
		(fp_line
			(start -0.7874 -0.4064)
			(end 0.7874 -0.4064)
			(stroke
				(width 0.1524)
				(type default)
			)
			(layer "F.SilkS")
		)
		(fp_line
			(start -0.7874 0.4064)
			(end -0.7874 -0.4064)
			(stroke
				(width 0.1524)
				(type default)
			)
			(layer "F.SilkS")
		)
		(fp_line
			(start 0 0.381)
			(end 0 -0.381)
			(stroke
				(width 0.1524)
				(type default)
			)
			(layer "F.SilkS")
		)
		(fp_line
			(start 0.7874 -0.4064)
			(end 0.7874 0.4064)
			(stroke
				(width 0.1524)
				(type default)
			)
			(layer "F.SilkS")
		)
		(fp_line
			(start 0.7874 0.4064)
			(end -0.7874 0.4064)
			(stroke
				(width 0.1524)
				(type default)
			)
			(layer "F.SilkS")
		)
		(fp_poly
			(pts
				(xy -0.5334 0.254) (xy -0.635 0.254) (xy -0.635 0.2286) (xy -0.635 -0.254) (xy -0.5334 -0.254) (xy -0.5334 -0.2794)
				(xy 0.5334 -0.2794) (xy 0.5334 -0.254) (xy 0.635 -0.254) (xy 0.635 0.254) (xy 0.5334 0.254) (xy 0.5334 0.2794)
				(xy -0.508 0.2794) (xy -0.5334 0.2794)
			)
			(stroke
				(width 0)
				(type default)
			)
			(fill no)
			(layer "F.CrtYd")
		)
		(pad "1" smd rect
			(at 0.40005 0)
			(size 0.4572 0.508)
			(layers "F.Cu" "F.Mask" "F.Paste")
			(net "P12V_AUX")
		)
		(pad "2" smd rect
			(at -0.40005 0)
			(size 0.4572 0.508)
			(layers "F.Cu" "F.Mask" "F.Paste")
			(net "GND")
		)
	)
	(footprint ""
		(layer "F.Cu")
		(at 171.05122 -49.05121)
		(property "Reference" "C559"
			(at -3.896614 2.135886 0)
			(unlocked yes)
			(layer "F.SilkS")
			(effects
				(font
					(size 0.7874 0.5842)
					(thickness 0.1524)
				)
				(justify left)
			)
		)
		(property "Value" ""
			(at 0 0 0)
			(layer "F.Fab")
			(effects
				(font
					(size 1.27 1.27)
				)
			)
		)
		(duplicate_pad_numbers_are_jumpers no)
		(fp_line
			(start -1.905 -0.8636)
			(end 1.905 -0.8636)
			(stroke
				(width 0.1524)
				(type default)
			)
			(layer "F.SilkS")
		)
		(fp_line
			(start -1.905 0.8636)
			(end -1.905 -0.8636)
			(stroke
				(width 0.1524)
				(type default)
			)
			(layer "F.SilkS")
		)
		(fp_line
			(start 0 0.8382)
			(end 0 -0.8382)
			(stroke
				(width 0.1524)
				(type default)
			)
			(layer "F.SilkS")
		)
		(fp_line
			(start 1.905 -0.8636)
			(end 1.905 0.8636)
			(stroke
				(width 0.1524)
				(type default)
			)
			(layer "F.SilkS")
		)
		(fp_line
			(start 1.905 0.8636)
			(end -1.905 0.8636)
			(stroke
				(width 0.1524)
				(type default)
			)
			(layer "F.SilkS")
		)
		(fp_rect
			(start -1.524 0.7366)
			(end 1.524 -0.7366)
			(stroke
				(width 0)
				(type default)
			)
			(fill no)
			(layer "F.CrtYd")
		)
		(pad "1" smd rect
			(at 0.94996 0)
			(size 1.1176 1.3716)
			(layers "F.Cu" "F.Mask" "F.Paste")
			(net "P5V_NODE1")
		)
		(pad "2" smd rect
			(at -0.94996 0)
			(size 1.1176 1.3716)
			(layers "F.Cu" "F.Mask" "F.Paste")
			(net "GND")
		)
	)
	(footprint ""
		(layer "F.Cu")
		(at 40.17391 -6.190742 180)
		(property "Reference" "PJ10"
			(at 9.209532 -1.064768 90)
			(unlocked yes)
			(layer "F.SilkS")
			(effects
				(font
					(size 0.7874 0.5842)
					(thickness 0.1524)
				)
				(justify left)
			)
		)
		(property "Value" ""
			(at 0 0 180)
			(layer "F.Fab")
			(effects
				(font
					(size 1.27 1.27)
				)
			)
		)
		(duplicate_pad_numbers_are_jumpers no)
		(fp_poly
			(pts
				(xy 0.2794 0.907796) (xy 0.254 0.907796) (xy 0.254 1.0414) (xy -0.254 1.0414) (xy -0.254 1.034796)
				(xy -0.254 0.933196) (xy -0.2794 0.933196) (xy -0.2794 -0.133604) (xy -0.254 -0.133604) (xy -0.254 -0.235204)
				(xy 0.254 -0.235204) (xy 0.254 -0.133604) (xy 0.2794 -0.133604)
			)
			(stroke
				(width 0)
				(type default)
			)
			(fill no)
			(layer "F.CrtYd")
		)
		(pad "1" smd custom
			(at 0 -0.000254 180)
			(size 0.127 0.127)
			(layers "F.Cu" "F.Mask" "F.Paste")
			(net "FM_CPLD_NODE1_PVDDR_STB_EN")
			(options
				(clearance outline)
				(anchor circle)
			)
			(primitives
				(gr_poly
					(pts
						(xy -0.127 0.508) (xy -0.127 -0.0508) (xy -0.254 -0.0508) (xy -0.254 -0.508) (xy 0.254 -0.508)
						(xy 0.254 -0.0508) (xy 0.127 -0.0508) (xy 0.127 0.508)
					)
					(width 0)
					(fill yes)
				)
			)
		)
		(pad "2" smd rect
			(at 0 0.799846 270)
			(size 0.4572 0.508)
			(layers "F.Cu" "F.Mask" "F.Paste")
			(net "PV_VDDR_NODE1_EN")
		)
		(zone
			(layer "F.Cu")
			(hatch none 0.5)
			(connect_pads
				(clearance 0)
			)
			(min_thickness 0.25)
			(keepout
				(tracks allowed)
				(vias not_allowed)
				(pads allowed)
				(copperpour not_allowed)
				(footprints allowed)
			)
			(placement
				(enabled no)
				(sheetname "")
			)
			(fill
				(thermal_gap 0.5)
				(thermal_bridge_width 0.5)
				(island_removal_mode 0)
			)
			(polygon
				(pts
					(xy 40.47871 -7.276338) (xy 39.86911 -7.276338) (xy 39.86911 -5.904738) (xy 40.47871 -5.904738)
				)
			)
		)
	)
)
